(kicad_pcb
	(version 20221018)
	(generator pcbnew)
	(general
    (thickness 1.6)
  )
	(paper "A4")
	(title_block
    (title "NUC Computer Cluster Power Breakout HW")
    (date "2023-10-18")
    (rev "1.4.3")
    (company "Antmicro Ltd.")
		(comment 9 "footprints 62-68 of 234")
	)
	(layers
    (0 "F.Cu" mixed)
    (1 "In1.Cu" power)
    (2 "In2.Cu" mixed)
    (31 "B.Cu" power)
    (32 "B.Adhes" user "B.Adhesive")
    (33 "F.Adhes" user "F.Adhesive")
    (34 "B.Paste" user)
    (35 "F.Paste" user)
    (36 "B.SilkS" user "B.Silkscreen")
    (37 "F.SilkS" user "F.Silkscreen")
    (38 "B.Mask" user)
    (39 "F.Mask" user)
    (40 "Dwgs.User" user "User.Drawings")
    (41 "Cmts.User" user "User.Comments")
    (42 "Eco1.User" user "User.Eco1")
    (43 "Eco2.User" user "User.Eco2")
    (44 "Edge.Cuts" user)
    (45 "Margin" user)
    (46 "B.CrtYd" user "B.Courtyard")
    (47 "F.CrtYd" user "F.Courtyard")
    (48 "B.Fab" user)
    (49 "F.Fab" user)
  )
	(footprint "antmicro-footprints:TSSOP-16_4.4x5mm_P0.65mm" (layer "F.Cu")
    (at 160 99.25 -90)
    (property "Author" "Antmicro")
    (property "License" "Apache-2.0")
    (property "MPN" "TCA9534PWR")
    (property "Manufacturer" "Texas Instruments")
    (property "Sheetfile" "pow-cycl-curr-meas.kicad_sch")
    (property "Sheetname" "Power Cycling & Current Measurement")
    (property "ki_description" "Low Voltage 8-Bit I2C and SMBUS Low-Power I/O Expander with Interrupt Output and Configuration Registers")
    (property "ki_keywords" "SMT, INTERFACE, IC, I2C")
    (attr smd)
    (fp_text reference "U10" (at 0.6 2.9 -90) (layer "F.SilkS")
        (effects (font (size 0.7 0.7) (thickness 0.15)) (justify left bottom))
    )
    (fp_text value "TCA9534PWR_TSSOP" (at 0.001 3.749 -90) (layer "F.Fab")
        (effects (font (size 0.7 0.7) (thickness 0.15)) (justify left bottom))
    )
    (fp_text user "Author: Antmicro" (at -3.81 6.949 -90) (layer "F.Fab") hide
        (effects (font (size 0.7 0.7) (thickness 0.15)) (justify left bottom))
    )
    (fp_text user "License: Apache-2.0" (at -3.81 5.749 -90) (layer "F.Fab") hide
        (effects (font (size 0.7 0.7) (thickness 0.15)) (justify left bottom))
    )
    (fp_text user "${REFERENCE}" (at -3.81 8.149 -90) (layer "F.Fab") hide
        (effects (font (size 0.7 0.7) (thickness 0.15)) (justify left bottom))
    )
    (fp_line (start -2.149 -2.735) (end 2.25 -2.735)
      (stroke (width 0.15) (type solid)) (layer "F.SilkS"))
    (fp_line (start 0.051 2.733) (end -2.149 2.733)
      (stroke (width 0.15) (type solid)) (layer "F.SilkS"))
    (fp_line (start 0.051 2.733) (end 2.25 2.733)
      (stroke (width 0.15) (type solid)) (layer "F.SilkS"))
    (fp_circle (center -2.815 -3.05) (end -2.765 -3.05)
      (stroke (width 0.15) (type solid)) (fill solid) (layer "F.SilkS"))
    (fp_line (start -3.81 -2.75) (end -3.81 2.74)
      (stroke (width 0.05) (type solid)) (layer "F.CrtYd"))
    (fp_line (start -3.81 2.74) (end 3.89 2.74)
      (stroke (width 0.05) (type solid)) (layer "F.CrtYd"))
    (fp_line (start 3.89 -2.75) (end -3.81 -2.75)
      (stroke (width 0.05) (type solid)) (layer "F.CrtYd"))
    (fp_line (start 3.89 2.74) (end 3.89 -2.75)
      (stroke (width 0.05) (type solid)) (layer "F.CrtYd"))
    (fp_line (start -2.149 -1.5) (end -1.15 -2.5)
      (stroke (width 0.15) (type solid)) (layer "F.Fab"))
    (fp_line (start -2.149 2.499) (end -2.149 -1.5)
      (stroke (width 0.15) (type solid)) (layer "F.Fab"))
    (fp_line (start -1.15 -2.5) (end 2.25 -2.5)
      (stroke (width 0.15) (type solid)) (layer "F.Fab"))
    (fp_line (start 2.25 -2.5) (end 2.25 2.499)
      (stroke (width 0.15) (type solid)) (layer "F.Fab"))
    (fp_line (start 2.25 2.499) (end -2.149 2.499)
      (stroke (width 0.15) (type solid)) (layer "F.Fab"))
    (pad "1" smd rect (at -2.815 -2.275 270) (size 1.475 0.4) (layers "F.Cu" "F.Paste" "F.Mask")
      (net 105 "Net-(U10-A0)") (pinfunction "A0") (pintype "input"))
    (pad "2" smd rect (at -2.815 -1.625 270) (size 1.475 0.4) (layers "F.Cu" "F.Paste" "F.Mask")
      (net 106 "Net-(U10-A1)") (pinfunction "A1") (pintype "input"))
    (pad "3" smd rect (at -2.815 -0.975 270) (size 1.475 0.4) (layers "F.Cu" "F.Paste" "F.Mask")
      (net 107 "Net-(U10-A2)") (pinfunction "A2") (pintype "input"))
    (pad "4" smd rect (at -2.815 -0.325 270) (size 1.475 0.4) (layers "F.Cu" "F.Paste" "F.Mask")
      (net 26 "/Power Cycling & Current Measurement/PC_5") (pinfunction "P0") (pintype "bidirectional"))
    (pad "5" smd rect (at -2.815 0.325 270) (size 1.475 0.4) (layers "F.Cu" "F.Paste" "F.Mask")
      (net 29 "/Power Cycling & Current Measurement/PC_4") (pinfunction "P1") (pintype "bidirectional"))
    (pad "6" smd rect (at -2.815 0.975 270) (size 1.475 0.4) (layers "F.Cu" "F.Paste" "F.Mask")
      (net 30 "/Power Cycling & Current Measurement/PC_3") (pinfunction "P2") (pintype "bidirectional"))
    (pad "7" smd rect (at -2.815 1.625 270) (size 1.475 0.4) (layers "F.Cu" "F.Paste" "F.Mask")
      (net 24 "/Power Cycling & Current Measurement/PC_2") (pinfunction "P3") (pintype "bidirectional"))
    (pad "8" smd rect (at -2.815 2.275 270) (size 1.475 0.4) (layers "F.Cu" "F.Paste" "F.Mask")
      (net 4 "GND") (pinfunction "GND") (pintype "power_in"))
    (pad "9" smd rect (at 2.91 2.275 270) (size 1.475 0.4) (layers "F.Cu" "F.Paste" "F.Mask")
      (net 23 "/Power Cycling & Current Measurement/PC_1") (pinfunction "P4") (pintype "bidirectional"))
    (pad "10" smd rect (at 2.91 1.625 270) (size 1.475 0.4) (layers "F.Cu" "F.Paste" "F.Mask")
      (net 160 "unconnected-(U10-P5-Pad10)") (pinfunction "P5") (pintype "bidirectional+no_connect"))
    (pad "11" smd rect (at 2.91 0.975 270) (size 1.475 0.4) (layers "F.Cu" "F.Paste" "F.Mask")
      (net 161 "unconnected-(U10-P6-Pad11)") (pinfunction "P6") (pintype "bidirectional+no_connect"))
    (pad "12" smd rect (at 2.91 0.325 270) (size 1.475 0.4) (layers "F.Cu" "F.Paste" "F.Mask")
      (net 162 "unconnected-(U10-P7-Pad12)") (pinfunction "P7") (pintype "bidirectional+no_connect"))
    (pad "13" smd rect (at 2.91 -0.325 270) (size 1.475 0.4) (layers "F.Cu" "F.Paste" "F.Mask")
      (net 108 "Net-(U10-~{INT})") (pinfunction "~{INT}") (pintype "open_collector"))
    (pad "14" smd rect (at 2.91 -0.975 270) (size 1.475 0.4) (layers "F.Cu" "F.Paste" "F.Mask")
      (net 17 "SCL") (pinfunction "SCL") (pintype "input"))
    (pad "15" smd rect (at 2.91 -1.625 270) (size 1.475 0.4) (layers "F.Cu" "F.Paste" "F.Mask")
      (net 18 "SDA") (pinfunction "SDA") (pintype "bidirectional"))
    (pad "16" smd rect (at 2.91 -2.275 270) (size 1.475 0.4) (layers "F.Cu" "F.Paste" "F.Mask")
      (net 1 "VCC3V3") (pinfunction "VCC") (pintype "power_in"))
  )
	(footprint "antmicro-footprints:TSSOP-16_4.4x5mm_P0.65mm" (layer "F.Cu")
    (at 152.1 99.25 -90)
    (property "Author" "Antmicro")
    (property "License" "Apache-2.0")
    (property "MPN" "ADS7828E/250")
    (property "Manufacturer" "Texas Instruments")
    (property "Sheetfile" "pow-cycl-curr-meas.kicad_sch")
    (property "Sheetname" "Power Cycling & Current Measurement")
    (property "ki_description" "8 channel12-bit ADC with I2C, 2V7-5V")
    (property "ki_keywords" "SMT, CONVERTER, IC, ADC, I2C")
    (attr smd)
    (fp_text reference "U14" (at 1.55 -3.75 -90) (layer "F.SilkS")
        (effects (font (size 0.7 0.7) (thickness 0.15)) (justify left bottom))
    )
    (fp_text value "ADS7828" (at 0.001 3.749 -90) (layer "F.Fab")
        (effects (font (size 0.7 0.7) (thickness 0.15)) (justify left bottom))
    )
    (fp_text user "${REFERENCE}" (at -3.81 8.149 -90) (layer "F.Fab") hide
        (effects (font (size 0.7 0.7) (thickness 0.15)) (justify left bottom))
    )
    (fp_text user "Author: Antmicro" (at -3.81 6.949 -90) (layer "F.Fab") hide
        (effects (font (size 0.7 0.7) (thickness 0.15)) (justify left bottom))
    )
    (fp_text user "License: Apache-2.0" (at -3.81 5.749 -90) (layer "F.Fab") hide
        (effects (font (size 0.7 0.7) (thickness 0.15)) (justify left bottom))
    )
    (fp_line (start -2.149 -2.735) (end 2.25 -2.735)
      (stroke (width 0.15) (type solid)) (layer "F.SilkS"))
    (fp_line (start 0.051 2.733) (end -2.149 2.733)
      (stroke (width 0.15) (type solid)) (layer "F.SilkS"))
    (fp_line (start 0.051 2.733) (end 2.25 2.733)
      (stroke (width 0.15) (type solid)) (layer "F.SilkS"))
    (fp_circle (center -2.815 -3.05) (end -2.765 -3.05)
      (stroke (width 0.15) (type solid)) (fill solid) (layer "F.SilkS"))
    (fp_line (start -3.81 -2.75) (end -3.81 2.74)
      (stroke (width 0.05) (type solid)) (layer "F.CrtYd"))
    (fp_line (start -3.81 2.74) (end 3.89 2.74)
      (stroke (width 0.05) (type solid)) (layer "F.CrtYd"))
    (fp_line (start 3.89 -2.75) (end -3.81 -2.75)
      (stroke (width 0.05) (type solid)) (layer "F.CrtYd"))
    (fp_line (start 3.89 2.74) (end 3.89 -2.75)
      (stroke (width 0.05) (type solid)) (layer "F.CrtYd"))
    (fp_line (start -2.149 -1.5) (end -1.15 -2.5)
      (stroke (width 0.15) (type solid)) (layer "F.Fab"))
    (fp_line (start -2.149 2.499) (end -2.149 -1.5)
      (stroke (width 0.15) (type solid)) (layer "F.Fab"))
    (fp_line (start -1.15 -2.5) (end 2.25 -2.5)
      (stroke (width 0.15) (type solid)) (layer "F.Fab"))
    (fp_line (start 2.25 -2.5) (end 2.25 2.499)
      (stroke (width 0.15) (type solid)) (layer "F.Fab"))
    (fp_line (start 2.25 2.499) (end -2.149 2.499)
      (stroke (width 0.15) (type solid)) (layer "F.Fab"))
    (pad "1" smd rect (at -2.815 -2.275 270) (size 1.475 0.4) (layers "F.Cu" "F.Paste" "F.Mask")
      (net 50 "/Power Cycling & Current Measurement/C_ADC5") (pinfunction "CH0") (pintype "input"))
    (pad "2" smd rect (at -2.815 -1.625 270) (size 1.475 0.4) (layers "F.Cu" "F.Paste" "F.Mask")
      (net 49 "/Power Cycling & Current Measurement/C_ADC4") (pinfunction "CH1") (pintype "input"))
    (pad "3" smd rect (at -2.815 -0.975 270) (size 1.475 0.4) (layers "F.Cu" "F.Paste" "F.Mask")
      (net 48 "/Power Cycling & Current Measurement/C_ADC3") (pinfunction "CH2") (pintype "input"))
    (pad "4" smd rect (at -2.815 -0.325 270) (size 1.475 0.4) (layers "F.Cu" "F.Paste" "F.Mask")
      (net 47 "/Power Cycling & Current Measurement/C_ADC2") (pinfunction "CH3") (pintype "input"))
    (pad "5" smd rect (at -2.815 0.325 270) (size 1.475 0.4) (layers "F.Cu" "F.Paste" "F.Mask")
      (net 46 "/Power Cycling & Current Measurement/C_ADC1") (pinfunction "CH4") (pintype "input"))
    (pad "6" smd rect (at -2.815 0.975 270) (size 1.475 0.4) (layers "F.Cu" "F.Paste" "F.Mask")
      (net 163 "unconnected-(U14-CH5-Pad6)") (pinfunction "CH5") (pintype "input+no_connect"))
    (pad "7" smd rect (at -2.815 1.625 270) (size 1.475 0.4) (layers "F.Cu" "F.Paste" "F.Mask")
      (net 164 "unconnected-(U14-CH6-Pad7)") (pinfunction "CH6") (pintype "input+no_connect"))
    (pad "8" smd rect (at -2.815 2.275 270) (size 1.475 0.4) (layers "F.Cu" "F.Paste" "F.Mask")
      (net 90 "/Power Cycling & Current Measurement/V_ADC1") (pinfunction "CH7") (pintype "input"))
    (pad "9" smd rect (at 2.91 2.275 270) (size 1.475 0.4) (layers "F.Cu" "F.Paste" "F.Mask")
      (net 4 "GND") (pinfunction "GND") (pintype "power_in"))
    (pad "10" smd rect (at 2.91 1.625 270) (size 1.475 0.4) (layers "F.Cu" "F.Paste" "F.Mask")
      (net 34 "Net-(U14-REF)") (pinfunction "REF") (pintype "bidirectional"))
    (pad "11" smd rect (at 2.91 0.975 270) (size 1.475 0.4) (layers "F.Cu" "F.Paste" "F.Mask")
      (net 4 "GND") (pinfunction "COM") (pintype "input"))
    (pad "12" smd rect (at 2.91 0.325 270) (size 1.475 0.4) (layers "F.Cu" "F.Paste" "F.Mask")
      (net 110 "Net-(U14-A0)") (pinfunction "A0") (pintype "input"))
    (pad "13" smd rect (at 2.91 -0.325 270) (size 1.475 0.4) (layers "F.Cu" "F.Paste" "F.Mask")
      (net 109 "Net-(U14-A1)") (pinfunction "A1") (pintype "input"))
    (pad "14" smd rect (at 2.91 -0.975 270) (size 1.475 0.4) (layers "F.Cu" "F.Paste" "F.Mask")
      (net 17 "SCL") (pinfunction "SCL") (pintype "input"))
    (pad "15" smd rect (at 2.91 -1.625 270) (size 1.475 0.4) (layers "F.Cu" "F.Paste" "F.Mask")
      (net 18 "SDA") (pinfunction "SDA") (pintype "bidirectional"))
    (pad "16" smd rect (at 2.91 -2.275 270) (size 1.475 0.4) (layers "F.Cu" "F.Paste" "F.Mask")
      (net 1 "VCC3V3") (pinfunction "VDD") (pintype "power_in"))
  )
	(footprint "antmicro-footprints:R_0402_1005Metric" (layer "F.Cu")
    (at 159.8 103.8)
    (descr "Resistor SMD 0402")
    (tags "resistor SMD 0402")
    (property "Author" "Antmicro")
    (property "License" "Apache-2.0")
    (property "MPN" "CR0402-FX-4701GLF")
    (property "Manufacturer" "Bourns")
    (property "Sheetfile" "pow-cycl-curr-meas.kicad_sch")
    (property "Sheetname" "Power Cycling & Current Measurement")
    (property "Tolerance" "1%")
    (property "Val" "4k7")
    (property "ki_description" "SMD Chip Resistor, 4.7 kohm, ± 1%, 62.5 mW, 0402 [1005 Metric], Thick Film, General Purpose")
    (property "ki_keywords" "0402, SMT, RESISTOR, PASSIVE")
    (attr smd)
    (fp_text reference "R19" (at -1.1 1.45) (layer "F.SilkS")
        (effects (font (size 0.7 0.7) (thickness 0.15)) (justify left bottom))
    )
    (fp_text value "R_4k7_0402" (at -1.011843 1.772047) (layer "F.Fab")
        (effects (font (size 0.7 0.7) (thickness 0.15)) (justify left bottom))
    )
    (fp_text user "License: Apache-2.0" (at -0.95 5.169) (layer "F.Fab") hide
        (effects (font (size 0.7 0.7) (thickness 0.15)) (justify left bottom))
    )
    (fp_text user "${REFERENCE}" (at -0.95 3.168) (layer "F.Fab") hide
        (effects (font (size 0.7 0.7) (thickness 0.15)) (justify left bottom))
    )
    (fp_text user "Author: Antmicro" (at -0.95 4.169) (layer "F.Fab") hide
        (effects (font (size 0.7 0.7) (thickness 0.15)) (justify left bottom))
    )
    (fp_rect (start -0.925 -0.47) (end 0.925 0.47)
      (stroke (width 0.05) (type default)) (fill none) (layer "F.CrtYd"))
    (fp_rect (start -0.5 -0.25) (end 0.5 0.25)
      (stroke (width 0.15) (type solid)) (fill none) (layer "F.Fab"))
    (pad "1" smd roundrect (at -0.48 0) (size 0.59 0.64) (layers "F.Cu" "F.Paste" "F.Mask") (roundrect_rratio 0.25)
      (net 1 "VCC3V3") (pintype "passive"))
    (pad "2" smd roundrect (at 0.48 0) (size 0.59 0.64) (layers "F.Cu" "F.Paste" "F.Mask") (roundrect_rratio 0.25)
      (net 108 "Net-(U10-~{INT})") (pintype "passive"))
  )
	(footprint "antmicro-footprints:TP_SMD_1mm" (layer "F.Cu")
    (at 126.4 82.0008)
    (property "Author" "Antmicro")
    (property "License" "Apache-2.0")
    (property "MPN" "")
    (property "Manufacturer" "")
    (property "Sheetfile" "pow-cycl-curr-meas.kicad_sch")
    (property "Sheetname" "Power Cycling & Current Measurement")
    (property "exclude_from_bom" "")
    (property "ki_description" "Test point 1mm SMD")
    (property "ki_keywords" "TESTPOINT")
    (attr exclude_from_pos_files exclude_from_bom)
    (fp_text reference "TP_ADC2" (at 0 -0.731898) (layer "F.SilkS") hide
        (effects (font (size 0.7 0.7) (thickness 0.15)) (justify left bottom))
    )
    (fp_text value "TP_1mm_SMD" (at 0 1.4) (layer "F.Fab")
        (effects (font (size 0.7 0.7) (thickness 0.15)) (justify left bottom))
    )
    (fp_text user "License: Apache-2.0" (at -0.5 5.2) (layer "F.Fab") hide
        (effects (font (size 0.7 0.7) (thickness 0.15)) (justify left bottom))
    )
    (fp_text user "${REFERENCE}" (at -0.5 2.8) (layer "F.Fab") hide
        (effects (font (size 0.7 0.7) (thickness 0.15)) (justify left bottom))
    )
    (fp_text user "Author: Antmicro" (at -0.5 4) (layer "F.Fab") hide
        (effects (font (size 0.7 0.7) (thickness 0.15)) (justify left bottom))
    )
    (fp_circle (center 0 0) (end 0.6 0)
      (stroke (width 0.05) (type default)) (fill none) (layer "F.CrtYd"))
    (pad "1" smd circle (at 0 0) (size 1 1) (layers "F.Cu" "F.Mask")
      (net 47 "/Power Cycling & Current Measurement/C_ADC2") (pinfunction "1") (pintype "passive"))
  )
	(footprint "antmicro-footprints:TP_SMD_1mm" (layer "F.Cu")
    (at 142.35 82.2008)
    (property "Author" "Antmicro")
    (property "License" "Apache-2.0")
    (property "MPN" "")
    (property "Manufacturer" "")
    (property "Sheetfile" "pow-cycl-curr-meas.kicad_sch")
    (property "Sheetname" "Power Cycling & Current Measurement")
    (property "exclude_from_bom" "")
    (property "ki_description" "Test point 1mm SMD")
    (property "ki_keywords" "TESTPOINT")
    (attr exclude_from_pos_files exclude_from_bom)
    (fp_text reference "TP_ADC3" (at 0 -0.731898) (layer "F.SilkS") hide
        (effects (font (size 0.7 0.7) (thickness 0.15)) (justify left bottom))
    )
    (fp_text value "TP_1mm_SMD" (at 0 1.4) (layer "F.Fab")
        (effects (font (size 0.7 0.7) (thickness 0.15)) (justify left bottom))
    )
    (fp_text user "Author: Antmicro" (at -0.5 4) (layer "F.Fab") hide
        (effects (font (size 0.7 0.7) (thickness 0.15)) (justify left bottom))
    )
    (fp_text user "License: Apache-2.0" (at -0.5 5.2) (layer "F.Fab") hide
        (effects (font (size 0.7 0.7) (thickness 0.15)) (justify left bottom))
    )
    (fp_text user "${REFERENCE}" (at -0.5 2.8) (layer "F.Fab") hide
        (effects (font (size 0.7 0.7) (thickness 0.15)) (justify left bottom))
    )
    (fp_circle (center 0 0) (end 0.6 0)
      (stroke (width 0.05) (type default)) (fill none) (layer "F.CrtYd"))
    (pad "1" smd circle (at 0 0) (size 1 1) (layers "F.Cu" "F.Mask")
      (net 48 "/Power Cycling & Current Measurement/C_ADC3") (pinfunction "1") (pintype "passive"))
  )
	(footprint "antmicro-footprints:TP_SMD_1mm" (layer "F.Cu")
    (at 159.35 82.0508)
    (property "Author" "Antmicro")
    (property "License" "Apache-2.0")
    (property "MPN" "")
    (property "Manufacturer" "")
    (property "Sheetfile" "pow-cycl-curr-meas.kicad_sch")
    (property "Sheetname" "Power Cycling & Current Measurement")
    (property "exclude_from_bom" "")
    (property "ki_description" "Test point 1mm SMD")
    (property "ki_keywords" "TESTPOINT")
    (attr exclude_from_pos_files exclude_from_bom)
    (fp_text reference "TP_ADC4" (at 0 -0.731898) (layer "F.SilkS") hide
        (effects (font (size 0.7 0.7) (thickness 0.15)) (justify left bottom))
    )
    (fp_text value "TP_1mm_SMD" (at 0 1.4) (layer "F.Fab")
        (effects (font (size 0.7 0.7) (thickness 0.15)) (justify left bottom))
    )
    (fp_text user "License: Apache-2.0" (at -0.5 5.2) (layer "F.Fab") hide
        (effects (font (size 0.7 0.7) (thickness 0.15)) (justify left bottom))
    )
    (fp_text user "${REFERENCE}" (at -0.5 2.8) (layer "F.Fab") hide
        (effects (font (size 0.7 0.7) (thickness 0.15)) (justify left bottom))
    )
    (fp_text user "Author: Antmicro" (at -0.5 4) (layer "F.Fab") hide
        (effects (font (size 0.7 0.7) (thickness 0.15)) (justify left bottom))
    )
    (fp_circle (center 0 0) (end 0.6 0)
      (stroke (width 0.05) (type default)) (fill none) (layer "F.CrtYd"))
    (pad "1" smd circle (at 0 0) (size 1 1) (layers "F.Cu" "F.Mask")
      (net 49 "/Power Cycling & Current Measurement/C_ADC4") (pinfunction "1") (pintype "passive"))
  )
	(footprint "antmicro-footprints:TP_SMD_1mm" (layer "F.Cu")
    (at 175.55 82.2508)
    (property "Author" "Antmicro")
    (property "License" "Apache-2.0")
    (property "MPN" "")
    (property "Manufacturer" "")
    (property "Sheetfile" "pow-cycl-curr-meas.kicad_sch")
    (property "Sheetname" "Power Cycling & Current Measurement")
    (property "exclude_from_bom" "")
    (property "ki_description" "Test point 1mm SMD")
    (property "ki_keywords" "TESTPOINT")
    (attr exclude_from_pos_files exclude_from_bom)
    (fp_text reference "TP_ADC5" (at 0 -0.731898) (layer "F.SilkS") hide
        (effects (font (size 0.7 0.7) (thickness 0.15)) (justify left bottom))
    )
    (fp_text value "TP_1mm_SMD" (at 0 1.4) (layer "F.Fab")
        (effects (font (size 0.7 0.7) (thickness 0.15)) (justify left bottom))
    )
    (fp_text user "${REFERENCE}" (at -0.5 2.8) (layer "F.Fab") hide
        (effects (font (size 0.7 0.7) (thickness 0.15)) (justify left bottom))
    )
    (fp_text user "License: Apache-2.0" (at -0.5 5.2) (layer "F.Fab") hide
        (effects (font (size 0.7 0.7) (thickness 0.15)) (justify left bottom))
    )
    (fp_text user "Author: Antmicro" (at -0.5 4) (layer "F.Fab") hide
        (effects (font (size 0.7 0.7) (thickness 0.15)) (justify left bottom))
    )
    (fp_circle (center 0 0) (end 0.6 0)
      (stroke (width 0.05) (type default)) (fill none) (layer "F.CrtYd"))
    (pad "1" smd circle (at 0 0) (size 1 1) (layers "F.Cu" "F.Mask")
      (net 50 "/Power Cycling & Current Measurement/C_ADC5") (pinfunction "1") (pintype "passive"))
  )
)
